(kicad_pcb
	(version 20260206)
	(generator "pcbnew")
	(generator_version "10.0")
	(general
		(thickness 1.6)
		(legacy_teardrops no)
	)
	(paper "A4")
	(title_block
		(title "Wiwynn_Tioga_Pass_MB.brd")
		(comment 1 "Tioga Pass / footprints 4731-4738 of 4770")
	)
	(layers
		(0 "F.Cu" signal "TOP")
		(4 "In1.Cu" signal "L2GND")
		(6 "In2.Cu" signal "L3")
		(8 "In3.Cu" signal "L4GND")
		(10 "In4.Cu" signal "L5")
		(12 "In5.Cu" signal "L6GND")
		(14 "In6.Cu" signal "L7VCC")
		(16 "In7.Cu" signal "L8VCC")
		(18 "In8.Cu" signal "L9GND")
		(20 "In9.Cu" signal "L10")
		(22 "In10.Cu" signal "L11GND")
		(24 "In11.Cu" signal "L12")
		(26 "In12.Cu" signal "L13GND")
		(2 "B.Cu" signal "BOTTOM")
		(9 "F.Adhes" user "F.Adhesive")
		(11 "B.Adhes" user "B.Adhesive")
		(13 "F.Paste" user "Package Geometry/Pastemask Top")
		(15 "B.Paste" user "Package Geometry/Pastemask Bottom")
		(5 "F.SilkS" user "Ref Des/Silkscreen Top")
		(7 "B.SilkS" user "Ref Des/Silkscreen Bottom")
		(1 "F.Mask" user "Board Geometry/Soldermask Top")
		(3 "B.Mask" user "Board Geometry/Soldermask Bottom")
		(17 "Dwgs.User" user "User.Drawings")
		(19 "Cmts.User" user "User.Comments")
		(21 "Eco1.User" user "User.Eco1")
		(23 "Eco2.User" user "User.Eco2")
		(25 "Edge.Cuts" user "Board Geometry/Outline")
		(27 "Margin" user)
		(31 "F.CrtYd" user "Package Geometry/Place Bound Top")
		(29 "B.CrtYd" user "Package Geometry/Place Bound Bottom")
		(35 "F.Fab" user "Ref Des/Assembly Top")
		(33 "B.Fab" user "Ref Des/Assembly Bottom")
	)
	(footprint ""
		(layer "B.Cu")
		(at 338.0232 -56.8833)
		(property "Reference" "R4R3"
			(at 0 0 0)
			(layer "B.SilkS")
			(hide yes)
			(effects
				(font
					(size 1.27 1.27)
				)
				(justify mirror)
			)
		)
		(property "Value" ""
			(at 0 0 0)
			(layer "B.Fab")
			(effects
				(font
					(size 1.27 1.27)
				)
				(justify mirror)
			)
		)
		(duplicate_pad_numbers_are_jumpers no)
		(fp_poly
			(pts
				(xy 0.2794 -0.1016) (xy -0.2794 -0.1016) (xy -0.2794 0.9906) (xy 0.2794 0.9906)
			)
			(stroke
				(width 0)
				(type default)
			)
			(fill no)
			(layer "B.CrtYd")
		)
		(fp_line
			(start -0.2794 -0.1016)
			(end 0.2794 -0.1016)
			(stroke
				(width 0.1)
				(type default)
			)
			(layer "B.Fab")
		)
		(fp_line
			(start -0.2794 0.9906)
			(end -0.2794 -0.1016)
			(stroke
				(width 0.1)
				(type default)
			)
			(layer "B.Fab")
		)
		(fp_line
			(start 0.2794 -0.1016)
			(end 0.2794 0.9906)
			(stroke
				(width 0.1)
				(type default)
			)
			(layer "B.Fab")
		)
		(fp_line
			(start 0.2794 0.9906)
			(end -0.2794 0.9906)
			(stroke
				(width 0.1)
				(type default)
			)
			(layer "B.Fab")
		)
		(pad "1" smd rect
			(at 0 0 180)
			(size 0.508 0.508)
			(layers "B.Cu" "B.Mask" "B.Paste")
			(net "PVCCIO_CPU0")
		)
		(pad "2" smd rect
			(at 0 0.889 180)
			(size 0.508 0.508)
			(layers "B.Cu" "B.Mask" "B.Paste")
			(net "H_CPU0_PROCHOT_G_N")
		)
		(zone
			(layer "B.Cu")
			(hatch none 0.5)
			(connect_pads
				(clearance 0)
			)
			(min_thickness 0.25)
			(keepout
				(tracks allowed)
				(vias not_allowed)
				(pads allowed)
				(copperpour not_allowed)
				(footprints allowed)
			)
			(placement
				(enabled no)
				(sheetname "")
			)
			(fill
				(thermal_gap 0.5)
				(thermal_bridge_width 0.5)
				(island_removal_mode 0)
			)
			(polygon
				(pts
					(xy 338.2772 -56.6293) (xy 337.7692 -56.6293) (xy 337.7692 -56.2483) (xy 338.2772 -56.2483)
				)
			)
		)
		(zone
			(layer "B.Cu")
			(hatch none 0.5)
			(connect_pads
				(clearance 0)
			)
			(min_thickness 0.25)
			(keepout
				(tracks not_allowed)
				(vias allowed)
				(pads allowed)
				(copperpour not_allowed)
				(footprints allowed)
			)
			(placement
				(enabled no)
				(sheetname "")
			)
			(fill
				(thermal_gap 0.5)
				(thermal_bridge_width 0.5)
				(island_removal_mode 0)
			)
			(polygon
				(pts
					(xy 338.2772 -56.2483) (xy 337.7692 -56.2483) (xy 337.7692 -56.6293) (xy 338.2772 -56.6293)
				)
			)
		)
	)
	(footprint ""
		(layer "B.Cu")
		(at 468.181944 -9.64692 180)
		(property "Reference" "R2U36"
			(at 0.8382 -0.67818 180)
			(unlocked yes)
			(layer "B.SilkS")
			(effects
				(font
					(size 0.4064 0.254)
					(thickness 0.1524)
				)
				(justify left mirror)
			)
		)
		(property "Value" ""
			(at 0 0 0)
			(layer "B.Fab")
			(effects
				(font
					(size 1.27 1.27)
				)
				(justify mirror)
			)
		)
		(duplicate_pad_numbers_are_jumpers no)
		(fp_poly
			(pts
				(xy 0.2794 -0.1016) (xy -0.2794 -0.1016) (xy -0.2794 0.9906) (xy 0.2794 0.9906)
			)
			(stroke
				(width 0)
				(type default)
			)
			(fill no)
			(layer "B.CrtYd")
		)
		(fp_line
			(start 0.2794 0.9906)
			(end -0.2794 0.9906)
			(stroke
				(width 0.1)
				(type default)
			)
			(layer "B.Fab")
		)
		(fp_line
			(start 0.2794 -0.1016)
			(end 0.2794 0.9906)
			(stroke
				(width 0.1)
				(type default)
			)
			(layer "B.Fab")
		)
		(fp_line
			(start -0.2794 0.9906)
			(end -0.2794 -0.1016)
			(stroke
				(width 0.1)
				(type default)
			)
			(layer "B.Fab")
		)
		(fp_line
			(start -0.2794 -0.1016)
			(end 0.2794 -0.1016)
			(stroke
				(width 0.1)
				(type default)
			)
			(layer "B.Fab")
		)
		(pad "1" smd rect
			(at 0 0)
			(size 0.508 0.508)
			(layers "B.Cu" "B.Mask" "B.Paste")
			(net "SMB_SLOTX24_PCH_STBY_LVC3_SCL")
		)
		(pad "2" smd rect
			(at 0 0.889)
			(size 0.508 0.508)
			(layers "B.Cu" "B.Mask" "B.Paste")
			(net "SMB_SLOTX24_STBY_LVC3_SCL_R2")
		)
		(zone
			(layer "B.Cu")
			(hatch none 0.5)
			(connect_pads
				(clearance 0)
			)
			(min_thickness 0.25)
			(keepout
				(tracks not_allowed)
				(vias allowed)
				(pads allowed)
				(copperpour not_allowed)
				(footprints allowed)
			)
			(placement
				(enabled no)
				(sheetname "")
			)
			(fill
				(thermal_gap 0.5)
				(thermal_bridge_width 0.5)
				(island_removal_mode 0)
			)
			(polygon
				(pts
					(xy 467.927944 -10.28192) (xy 468.435944 -10.28192) (xy 468.435944 -9.90092) (xy 467.927944 -9.90092)
				)
			)
		)
		(zone
			(layer "B.Cu")
			(hatch none 0.5)
			(connect_pads
				(clearance 0)
			)
			(min_thickness 0.25)
			(keepout
				(tracks allowed)
				(vias not_allowed)
				(pads allowed)
				(copperpour not_allowed)
				(footprints allowed)
			)
			(placement
				(enabled no)
				(sheetname "")
			)
			(fill
				(thermal_gap 0.5)
				(thermal_bridge_width 0.5)
				(island_removal_mode 0)
			)
			(polygon
				(pts
					(xy 467.927944 -9.90092) (xy 468.435944 -9.90092) (xy 468.435944 -10.28192) (xy 467.927944 -10.28192)
				)
			)
		)
	)
	(footprint ""
		(layer "B.Cu")
		(at 348.713806 -61.257434)
		(property "Reference" "C2U14"
			(at 0 0 0)
			(layer "B.SilkS")
			(hide yes)
			(effects
				(font
					(size 1.27 1.27)
				)
				(justify mirror)
			)
		)
		(property "Value" ""
			(at 0 0 0)
			(layer "B.Fab")
			(effects
				(font
					(size 1.27 1.27)
				)
				(justify mirror)
			)
		)
		(duplicate_pad_numbers_are_jumpers no)
		(fp_poly
			(pts
				(xy -0.3048 -0.1016) (xy -0.3048 0.9906) (xy 0.3048 0.9906) (xy 0.3048 -0.1016)
			)
			(stroke
				(width 0)
				(type default)
			)
			(fill no)
			(layer "B.CrtYd")
		)
		(fp_line
			(start -0.3048 -0.1016)
			(end 0.3048 -0.1016)
			(stroke
				(width 0.1)
				(type default)
			)
			(layer "B.Fab")
		)
		(fp_line
			(start -0.3048 0.9906)
			(end -0.3048 -0.1016)
			(stroke
				(width 0.1)
				(type default)
			)
			(layer "B.Fab")
		)
		(fp_line
			(start 0.3048 -0.1016)
			(end 0.3048 0.9906)
			(stroke
				(width 0.1)
				(type default)
			)
			(layer "B.Fab")
		)
		(fp_line
			(start 0.3048 0.9906)
			(end -0.3048 0.9906)
			(stroke
				(width 0.1)
				(type default)
			)
			(layer "B.Fab")
		)
		(pad "1" smd rect
			(at 0 0 180)
			(size 0.508 0.508)
			(layers "B.Cu" "B.Mask" "B.Paste")
			(net "P3E_CPU0_PE1_PCH_RXN<5>")
		)
		(pad "2" smd rect
			(at 0 0.889 180)
			(size 0.508 0.508)
			(layers "B.Cu" "B.Mask" "B.Paste")
			(net "P3E_CPU0_PE1_SS_RXN<5>")
		)
		(zone
			(layer "B.Cu")
			(hatch none 0.5)
			(connect_pads
				(clearance 0)
			)
			(min_thickness 0.25)
			(keepout
				(tracks allowed)
				(vias not_allowed)
				(pads allowed)
				(copperpour not_allowed)
				(footprints allowed)
			)
			(placement
				(enabled no)
				(sheetname "")
			)
			(fill
				(thermal_gap 0.5)
				(thermal_bridge_width 0.5)
				(island_removal_mode 0)
			)
			(polygon
				(pts
					(xy 348.967806 -61.003434) (xy 348.459806 -61.003434) (xy 348.459806 -60.622434) (xy 348.967806 -60.622434)
				)
			)
		)
	)
	(footprint ""
		(layer "B.Cu")
		(at 197.866 -100.584 90)
		(property "Reference" "C6N2"
			(at 0 0 90)
			(layer "B.SilkS")
			(hide yes)
			(effects
				(font
					(size 1.27 1.27)
				)
				(justify mirror)
			)
		)
		(property "Value" ""
			(at 0 0 90)
			(layer "B.Fab")
			(effects
				(font
					(size 1.27 1.27)
				)
				(justify mirror)
			)
		)
		(duplicate_pad_numbers_are_jumpers no)
		(fp_rect
			(start -0.7239 -0.2159)
			(end 0.7239 1.9939)
			(stroke
				(width 0)
				(type default)
			)
			(fill no)
			(layer "B.CrtYd")
		)
		(fp_line
			(start 0.7239 -0.2159)
			(end 0.7239 1.9939)
			(stroke
				(width 0.1)
				(type default)
			)
			(layer "B.Fab")
		)
		(fp_line
			(start -0.7239 -0.2159)
			(end 0.7239 -0.2159)
			(stroke
				(width 0.1)
				(type default)
			)
			(layer "B.Fab")
		)
		(fp_line
			(start 0.7239 1.9939)
			(end -0.7239 1.9939)
			(stroke
				(width 0.1)
				(type default)
			)
			(layer "B.Fab")
		)
		(fp_line
			(start -0.7239 1.9939)
			(end -0.7239 -0.2159)
			(stroke
				(width 0.1)
				(type default)
			)
			(layer "B.Fab")
		)
		(pad "1" smd rect
			(at 0 0 270)
			(size 1.27 1.016)
			(layers "B.Cu" "B.Mask" "B.Paste")
			(net "VR_FET_SW_P12V_STBY_PVCCIN_CPU0")
		)
		(pad "2" smd rect
			(at 0 1.778 270)
			(size 1.27 1.016)
			(layers "B.Cu" "B.Mask" "B.Paste")
			(net "GND")
		)
		(zone
			(layer "B.Cu")
			(hatch none 0.5)
			(connect_pads
				(clearance 0)
			)
			(min_thickness 0.25)
			(keepout
				(tracks not_allowed)
				(vias allowed)
				(pads allowed)
				(copperpour not_allowed)
				(footprints allowed)
			)
			(placement
				(enabled no)
				(sheetname "")
			)
			(fill
				(thermal_gap 0.5)
				(thermal_bridge_width 0.5)
				(island_removal_mode 0)
			)
			(polygon
				(pts
					(xy 198.374 -99.949) (xy 199.136 -99.949) (xy 199.136 -101.219) (xy 198.374 -101.219)
				)
			)
		)
	)
	(footprint ""
		(layer "B.Cu")
		(at 111.000032 -140.208 90)
		(property "Reference" "C5G109"
			(at -1.14681 0.76708 180)
			(unlocked yes)
			(layer "B.SilkS")
			(effects
				(font
					(size 0.7874 0.5842)
					(thickness 0.1524)
				)
				(justify mirror)
			)
		)
		(property "Value" ""
			(at 0 0 90)
			(layer "B.Fab")
			(effects
				(font
					(size 1.27 1.27)
				)
				(justify mirror)
			)
		)
		(duplicate_pad_numbers_are_jumpers no)
		(fp_rect
			(start -0.4953 -0.2032)
			(end 0.4953 1.6002)
			(stroke
				(width 0)
				(type default)
			)
			(fill no)
			(layer "B.CrtYd")
		)
		(fp_line
			(start 0.4953 -0.2032)
			(end -0.4953 -0.2032)
			(stroke
				(width 0.1)
				(type default)
			)
			(layer "B.Fab")
		)
		(fp_line
			(start -0.4953 -0.2032)
			(end -0.4953 1.6002)
			(stroke
				(width 0.1)
				(type default)
			)
			(layer "B.Fab")
		)
		(fp_line
			(start 0.4953 1.6002)
			(end 0.4953 -0.2032)
			(stroke
				(width 0.1)
				(type default)
			)
			(layer "B.Fab")
		)
		(fp_line
			(start -0.4953 1.6002)
			(end 0.4953 1.6002)
			(stroke
				(width 0.1)
				(type default)
			)
			(layer "B.Fab")
		)
		(pad "1" smd rect
			(at 0 0 270)
			(size 0.762 0.889)
			(layers "B.Cu" "B.Mask" "B.Paste")
			(net "PVDDQ_KLM")
		)
		(pad "2" smd rect
			(at 0 1.397 270)
			(size 0.762 0.889)
			(layers "B.Cu" "B.Mask" "B.Paste")
			(net "GND")
		)
		(zone
			(layer "B.Cu")
			(hatch none 0.5)
			(connect_pads
				(clearance 0)
			)
			(min_thickness 0.25)
			(keepout
				(tracks not_allowed)
				(vias allowed)
				(pads allowed)
				(copperpour not_allowed)
				(footprints allowed)
			)
			(placement
				(enabled no)
				(sheetname "")
			)
			(fill
				(thermal_gap 0.5)
				(thermal_bridge_width 0.5)
				(island_removal_mode 0)
			)
			(polygon
				(pts
					(xy 111.444532 -139.827) (xy 111.952532 -139.827) (xy 111.952532 -140.589) (xy 111.444532 -140.589)
				)
			)
		)
	)
	(footprint ""
		(layer "B.Cu")
		(at 420.077646 -45.539152)
		(property "Reference" "R25W97"
			(at 0.8382 -0.67818 0)
			(unlocked yes)
			(layer "B.SilkS")
			(effects
				(font
					(size 0.4064 0.254)
					(thickness 0.1524)
				)
				(justify left mirror)
			)
		)
		(property "Value" ""
			(at 0 0 0)
			(layer "B.Fab")
			(effects
				(font
					(size 1.27 1.27)
				)
				(justify mirror)
			)
		)
		(duplicate_pad_numbers_are_jumpers no)
		(fp_poly
			(pts
				(xy 0.2794 -0.1016) (xy -0.2794 -0.1016) (xy -0.2794 0.9906) (xy 0.2794 0.9906)
			)
			(stroke
				(width 0)
				(type default)
			)
			(fill no)
			(layer "B.CrtYd")
		)
		(fp_line
			(start -0.2794 -0.1016)
			(end 0.2794 -0.1016)
			(stroke
				(width 0.1)
				(type default)
			)
			(layer "B.Fab")
		)
		(fp_line
			(start -0.2794 0.9906)
			(end -0.2794 -0.1016)
			(stroke
				(width 0.1)
				(type default)
			)
			(layer "B.Fab")
		)
		(fp_line
			(start 0.2794 -0.1016)
			(end 0.2794 0.9906)
			(stroke
				(width 0.1)
				(type default)
			)
			(layer "B.Fab")
		)
		(fp_line
			(start 0.2794 0.9906)
			(end -0.2794 0.9906)
			(stroke
				(width 0.1)
				(type default)
			)
			(layer "B.Fab")
		)
		(pad "1" smd rect
			(at 0 0 180)
			(size 0.508 0.508)
			(layers "B.Cu" "B.Mask" "B.Paste")
			(net "P3V3_STBY")
		)
		(pad "2" smd rect
			(at 0 0.889 180)
			(size 0.508 0.508)
			(layers "B.Cu" "B.Mask" "B.Paste")
			(net "SPI_BMC_BT_DI")
		)
		(zone
			(layer "B.Cu")
			(hatch none 0.5)
			(connect_pads
				(clearance 0)
			)
			(min_thickness 0.25)
			(keepout
				(tracks allowed)
				(vias not_allowed)
				(pads allowed)
				(copperpour not_allowed)
				(footprints allowed)
			)
			(placement
				(enabled no)
				(sheetname "")
			)
			(fill
				(thermal_gap 0.5)
				(thermal_bridge_width 0.5)
				(island_removal_mode 0)
			)
			(polygon
				(pts
					(xy 420.331646 -45.285152) (xy 419.823646 -45.285152) (xy 419.823646 -44.904152) (xy 420.331646 -44.904152)
				)
			)
		)
		(zone
			(layer "B.Cu")
			(hatch none 0.5)
			(connect_pads
				(clearance 0)
			)
			(min_thickness 0.25)
			(keepout
				(tracks not_allowed)
				(vias allowed)
				(pads allowed)
				(copperpour not_allowed)
				(footprints allowed)
			)
			(placement
				(enabled no)
				(sheetname "")
			)
			(fill
				(thermal_gap 0.5)
				(thermal_bridge_width 0.5)
				(island_removal_mode 0)
			)
			(polygon
				(pts
					(xy 420.331646 -44.904152) (xy 419.823646 -44.904152) (xy 419.823646 -45.285152) (xy 420.331646 -45.285152)
				)
			)
		)
	)
	(footprint ""
		(layer "B.Cu")
		(at 415.708846 -44.650152 180)
		(property "Reference" "R9F22"
			(at 0 0 0)
			(layer "B.SilkS")
			(hide yes)
			(effects
				(font
					(size 1.27 1.27)
				)
				(justify mirror)
			)
		)
		(property "Value" ""
			(at 0 0 0)
			(layer "B.Fab")
			(effects
				(font
					(size 1.27 1.27)
				)
				(justify mirror)
			)
		)
		(duplicate_pad_numbers_are_jumpers no)
		(fp_poly
			(pts
				(xy 0.2794 -0.1016) (xy -0.2794 -0.1016) (xy -0.2794 0.9906) (xy 0.2794 0.9906)
			)
			(stroke
				(width 0)
				(type default)
			)
			(fill no)
			(layer "B.CrtYd")
		)
		(fp_line
			(start 0.2794 0.9906)
			(end -0.2794 0.9906)
			(stroke
				(width 0.1)
				(type default)
			)
			(layer "B.Fab")
		)
		(fp_line
			(start 0.2794 -0.1016)
			(end 0.2794 0.9906)
			(stroke
				(width 0.1)
				(type default)
			)
			(layer "B.Fab")
		)
		(fp_line
			(start -0.2794 0.9906)
			(end -0.2794 -0.1016)
			(stroke
				(width 0.1)
				(type default)
			)
			(layer "B.Fab")
		)
		(fp_line
			(start -0.2794 -0.1016)
			(end 0.2794 -0.1016)
			(stroke
				(width 0.1)
				(type default)
			)
			(layer "B.Fab")
		)
		(pad "1" smd rect
			(at 0 0)
			(size 0.508 0.508)
			(layers "B.Cu" "B.Mask" "B.Paste")
			(net "SMB_LAN_STBY_LVC3_SCL_R")
		)
		(pad "2" smd rect
			(at 0 0.889)
			(size 0.508 0.508)
			(layers "B.Cu" "B.Mask" "B.Paste")
			(net "SMB_LAN_STBY_LVC3_SCL")
		)
		(zone
			(layer "B.Cu")
			(hatch none 0.5)
			(connect_pads
				(clearance 0)
			)
			(min_thickness 0.25)
			(keepout
				(tracks not_allowed)
				(vias allowed)
				(pads allowed)
				(copperpour not_allowed)
				(footprints allowed)
			)
			(placement
				(enabled no)
				(sheetname "")
			)
			(fill
				(thermal_gap 0.5)
				(thermal_bridge_width 0.5)
				(island_removal_mode 0)
			)
			(polygon
				(pts
					(xy 415.454846 -45.285152) (xy 415.962846 -45.285152) (xy 415.962846 -44.904152) (xy 415.454846 -44.904152)
				)
			)
		)
		(zone
			(layer "B.Cu")
			(hatch none 0.5)
			(connect_pads
				(clearance 0)
			)
			(min_thickness 0.25)
			(keepout
				(tracks allowed)
				(vias not_allowed)
				(pads allowed)
				(copperpour not_allowed)
				(footprints allowed)
			)
			(placement
				(enabled no)
				(sheetname "")
			)
			(fill
				(thermal_gap 0.5)
				(thermal_bridge_width 0.5)
				(island_removal_mode 0)
			)
			(polygon
				(pts
					(xy 415.454846 -44.904152) (xy 415.962846 -44.904152) (xy 415.962846 -45.285152) (xy 415.454846 -45.285152)
				)
			)
		)
	)
	(footprint ""
		(layer "B.Cu")
		(at 402.805646 -27.124152)
		(property "Reference" "R1U33"
			(at 0 0 0)
			(layer "B.SilkS")
			(hide yes)
			(effects
				(font
					(size 1.27 1.27)
				)
				(justify mirror)
			)
		)
		(property "Value" "*"
			(at -0.064008 -4.108196 0)
			(unlocked yes)
			(layer "B.Fab")
			(hide yes)
			(effects
				(font
					(size 1.27 1.016)
					(thickness 0.1524)
				)
				(justify mirror)
			)
		)
		(property "Device Type" "649R2F-GP_RCL_GP-649R2F-GP,64.A"
			(at -0.064008 -5.632196 0)
			(unlocked yes)
			(layer "B.Fab")
			(hide yes)
			(effects
				(font
					(size 1.27 1.016)
					(thickness 0.1524)
				)
				(justify mirror)
			)
		)
		(duplicate_pad_numbers_are_jumpers no)
		(fp_line
			(start -0.508 -0.9398)
			(end 0.508 -0.9398)
			(stroke
				(width 0.1524)
				(type default)
			)
			(layer "B.SilkS")
		)
		(fp_line
			(start 0.508 -0.9398)
			(end 0.508 0.9398)
			(stroke
				(width 0.1524)
				(type default)
			)
			(layer "B.SilkS")
		)
		(fp_rect
			(start 0.508 0.9398)
			(end -0.508 -0.9398)
			(stroke
				(width 0)
				(type default)
			)
			(fill no)
			(layer "B.CrtYd")
		)
		(fp_rect
			(start 0.508 0.9398)
			(end -0.508 -0.9398)
			(stroke
				(width 0)
				(type default)
			)
			(fill no)
			(layer "B.Fab")
		)
		(pad "1" smd custom
			(at 0 -0.4445 180)
			(size 0.1397 0.1397)
			(layers "B.Cu" "B.Mask" "B.Paste")
			(net "A_P12V_STBY_SCALED")
			(options
				(clearance outline)
				(anchor circle)
			)
			(primitives
				(gr_poly
					(pts
						(arc
							(start -0.1778 0.2794)
							(mid -0.249642 0.249642)
							(end -0.2794 0.1778)
						)
						(arc
							(start -0.2794 -0.1778)
							(mid -0.249642 -0.249642)
							(end -0.1778 -0.2794)
						)
						(arc
							(start 0.1778 -0.2794)
							(mid 0.249642 -0.249642)
							(end 0.2794 -0.1778)
						)
						(arc
							(start 0.2794 0.1778)
							(mid 0.249642 0.249642)
							(end 0.1778 0.2794)
						)
					)
					(width 0)
					(fill yes)
				)
			)
		)
		(pad "2" smd custom
			(at 0 0.4445 180)
			(size 0.1397 0.1397)
			(layers "B.Cu" "B.Mask" "B.Paste")
			(net "GND")
			(options
				(clearance outline)
				(anchor circle)
			)
			(primitives
				(gr_poly
					(pts
						(arc
							(start -0.1778 0.2794)
							(mid -0.249642 0.249642)
							(end -0.2794 0.1778)
						)
						(arc
							(start -0.2794 -0.1778)
							(mid -0.249642 -0.249642)
							(end -0.1778 -0.2794)
						)
						(arc
							(start 0.1778 -0.2794)
							(mid 0.249642 -0.249642)
							(end 0.2794 -0.1778)
						)
						(arc
							(start 0.2794 0.1778)
							(mid 0.249642 0.249642)
							(end 0.1778 0.2794)
						)
					)
					(width 0)
					(fill yes)
				)
			)
		)
	)
)
